# BASEBOARD_FAB2 (Tioga Pass) — schematic netlist excerpt (pin names and nets, part order shuffled) for the footprints in the layout excerpt that follows; sources: Cadence DE-HDL packaged netlist, KiCad conversion of Wiwynn_Tioga_Pass_MB.brd

FB2T5  HCB1608KF-800T30-GP  pkg DISCRET-G9  page 149 : \1\ = P3V3_STBY ; \2\ = VCC_PA_3V3
C3P4  CAP_A  1.0UF 6.3V 10% X6S  pkg 0402V  page 211 : A = VR_PVCCIO_CPU0_VD12 ; B = GND
C1M24  CAP_A  0.1UF 16V 10% X7R  pkg 0402V  page 186 : A = P3V3 ; B = GND

(kicad_pcb
	(version 20260206)
	(generator "pcbnew")
	(generator_version "10.0")
	(general
		(thickness 1.6)
		(legacy_teardrops no)
	)
	(paper "A4")
	(title_block
		(title "Wiwynn_Tioga_Pass_MB.brd")
		(comment 1 "Tioga Pass / footprints 3993-3995 of 4770")
	)
	(layers
		(0 "F.Cu" signal "TOP")
		(4 "In1.Cu" signal "L2GND")
		(6 "In2.Cu" signal "L3")
		(8 "In3.Cu" signal "L4GND")
		(10 "In4.Cu" signal "L5")
		(12 "In5.Cu" signal "L6GND")
		(14 "In6.Cu" signal "L7VCC")
		(16 "In7.Cu" signal "L8VCC")
		(18 "In8.Cu" signal "L9GND")
		(20 "In9.Cu" signal "L10")
		(22 "In10.Cu" signal "L11GND")
		(24 "In11.Cu" signal "L12")
		(26 "In12.Cu" signal "L13GND")
		(2 "B.Cu" signal "BOTTOM")
		(9 "F.Adhes" user "F.Adhesive")
		(11 "B.Adhes" user "B.Adhesive")
		(13 "F.Paste" user "Package Geometry/Pastemask Top")
		(15 "B.Paste" user "Package Geometry/Pastemask Bottom")
		(5 "F.SilkS" user "Ref Des/Silkscreen Top")
		(7 "B.SilkS" user "Ref Des/Silkscreen Bottom")
		(1 "F.Mask" user "Board Geometry/Soldermask Top")
		(3 "B.Mask" user "Board Geometry/Soldermask Bottom")
		(17 "Dwgs.User" user "User.Drawings")
		(19 "Cmts.User" user "User.Comments")
		(21 "Eco1.User" user "User.Eco1")
		(23 "Eco2.User" user "User.Eco2")
		(25 "Edge.Cuts" user "Board Geometry/Outline")
		(27 "Margin" user)
		(31 "F.CrtYd" user "Package Geometry/Place Bound Top")
		(29 "B.CrtYd" user "Package Geometry/Place Bound Bottom")
		(35 "F.Fab" user "Ref Des/Assembly Top")
		(33 "B.Fab" user "Ref Des/Assembly Bottom")
	)
	(footprint ""
		(layer "B.Cu")
		(at 481.3808 -113.1062 90)
		(property "Reference" "C1M24"
			(at 0 0 90)
			(layer "B.SilkS")
			(hide yes)
			(effects
				(font
					(size 1.27 1.27)
				)
				(justify mirror)
			)
		)
		(property "Value" ""
			(at 0 0 90)
			(layer "B.Fab")
			(effects
				(font
					(size 1.27 1.27)
				)
				(justify mirror)
			)
		)
		(duplicate_pad_numbers_are_jumpers no)
		(fp_rect
			(start 0.3048 0.9906)
			(end -0.3048 -0.1016)
			(stroke
				(width 0)
				(type default)
			)
			(fill no)
			(layer "B.CrtYd")
		)
		(fp_line
			(start 0.3048 -0.1016)
			(end 0.3048 0.9906)
			(stroke
				(width 0.1)
				(type default)
			)
			(layer "B.Fab")
		)
		(fp_line
			(start -0.3048 -0.1016)
			(end 0.3048 -0.1016)
			(stroke
				(width 0.1)
				(type default)
			)
			(layer "B.Fab")
		)
		(fp_line
			(start 0.3048 0.9906)
			(end -0.3048 0.9906)
			(stroke
				(width 0.1)
				(type default)
			)
			(layer "B.Fab")
		)
		(fp_line
			(start -0.3048 0.9906)
			(end -0.3048 -0.1016)
			(stroke
				(width 0.1)
				(type default)
			)
			(layer "B.Fab")
		)
		(pad "1" smd rect
			(at 0 0 270)
			(size 0.508 0.508)
			(layers "B.Cu" "B.Mask" "B.Paste")
			(net "P3V3")
		)
		(pad "2" smd rect
			(at 0 0.889 270)
			(size 0.508 0.508)
			(layers "B.Cu" "B.Mask" "B.Paste")
			(net "GND")
		)
		(zone
			(layer "B.Cu")
			(hatch none 0.5)
			(connect_pads
				(clearance 0)
			)
			(min_thickness 0.25)
			(keepout
				(tracks allowed)
				(vias not_allowed)
				(pads allowed)
				(copperpour not_allowed)
				(footprints allowed)
			)
			(placement
				(enabled no)
				(sheetname "")
			)
			(fill
				(thermal_gap 0.5)
				(thermal_bridge_width 0.5)
				(island_removal_mode 0)
			)
			(polygon
				(pts
					(xy 482.0158 -113.3602) (xy 481.6348 -113.3602) (xy 481.6348 -112.8522) (xy 482.0158 -112.8522)
				)
			)
		)
		(zone
			(layer "B.Cu")
			(hatch none 0.5)
			(connect_pads
				(clearance 0)
			)
			(min_thickness 0.25)
			(keepout
				(tracks not_allowed)
				(vias allowed)
				(pads allowed)
				(copperpour not_allowed)
				(footprints allowed)
			)
			(placement
				(enabled no)
				(sheetname "")
			)
			(fill
				(thermal_gap 0.5)
				(thermal_bridge_width 0.5)
				(island_removal_mode 0)
			)
			(polygon
				(pts
					(xy 482.0158 -113.3602) (xy 481.6348 -113.3602) (xy 481.6348 -112.8522) (xy 482.0158 -112.8522)
				)
			)
		)
	)
	(footprint ""
		(layer "B.Cu")
		(at 427.482 -42.0751 -90)
		(property "Reference" "FB2T5"
			(at 0 0 90)
			(layer "B.SilkS")
			(hide yes)
			(effects
				(font
					(size 1.27 1.27)
				)
				(justify mirror)
			)
		)
		(property "Value" "*"
			(at -0.0254 -2.8829 270)
			(unlocked yes)
			(layer "B.Fab")
			(hide yes)
			(effects
				(font
					(size 1.27 1.016)
					(thickness 0.1524)
				)
				(justify mirror)
			)
		)
		(property "Device Type" "HCB1608KF-800T30-GP_DISCRET-G9A"
			(at -0.0254 -4.4069 270)
			(unlocked yes)
			(layer "B.Fab")
			(hide yes)
			(effects
				(font
					(size 1.27 1.016)
					(thickness 0.1524)
				)
				(justify mirror)
			)
		)
		(duplicate_pad_numbers_are_jumpers no)
		(fp_line
			(start -0.254 0)
			(end 0.254 0)
			(stroke
				(width 0.2032)
				(type default)
			)
			(layer "B.SilkS")
		)
		(fp_rect
			(start 0.5842 1.3335)
			(end -0.5842 -1.3335)
			(stroke
				(width 0)
				(type default)
			)
			(fill no)
			(layer "B.CrtYd")
		)
		(fp_rect
			(start 0.5842 1.3335)
			(end -0.5842 -1.3335)
			(stroke
				(width 0)
				(type default)
			)
			(fill no)
			(layer "B.Fab")
		)
		(pad "1" smd custom
			(at 0 -0.762 90)
			(size 0.2159 0.2159)
			(layers "B.Cu" "B.Mask" "B.Paste")
			(net "P3V3_STBY")
			(options
				(clearance outline)
				(anchor circle)
			)
			(primitives
				(gr_poly
					(pts
						(arc
							(start -0.3302 0.4318)
							(mid -0.402042 0.402042)
							(end -0.4318 0.3302)
						)
						(arc
							(start -0.4318 -0.3302)
							(mid -0.402042 -0.402042)
							(end -0.3302 -0.4318)
						)
						(arc
							(start 0.3302 -0.4318)
							(mid 0.402042 -0.402042)
							(end 0.4318 -0.3302)
						)
						(arc
							(start 0.4318 0.3302)
							(mid 0.402042 0.402042)
							(end 0.3302 0.4318)
						)
					)
					(width 0)
					(fill yes)
				)
			)
		)
		(pad "2" smd custom
			(at 0 0.762 90)
			(size 0.2159 0.2159)
			(layers "B.Cu" "B.Mask" "B.Paste")
			(net "VCC_PA_3V3")
			(options
				(clearance outline)
				(anchor circle)
			)
			(primitives
				(gr_poly
					(pts
						(arc
							(start -0.3302 0.4318)
							(mid -0.402042 0.402042)
							(end -0.4318 0.3302)
						)
						(arc
							(start -0.4318 -0.3302)
							(mid -0.402042 -0.402042)
							(end -0.3302 -0.4318)
						)
						(arc
							(start 0.3302 -0.4318)
							(mid 0.402042 -0.402042)
							(end 0.4318 -0.3302)
						)
						(arc
							(start 0.4318 0.3302)
							(mid 0.402042 0.402042)
							(end 0.3302 0.4318)
						)
					)
					(width 0)
					(fill yes)
				)
			)
		)
	)
	(footprint ""
		(layer "B.Cu")
		(at 348.234 -83.5406)
		(property "Reference" "C3P4"
			(at 0 0 0)
			(layer "B.SilkS")
			(hide yes)
			(effects
				(font
					(size 1.27 1.27)
				)
				(justify mirror)
			)
		)
		(property "Value" ""
			(at 0 0 0)
			(layer "B.Fab")
			(effects
				(font
					(size 1.27 1.27)
				)
				(justify mirror)
			)
		)
		(duplicate_pad_numbers_are_jumpers no)
		(fp_poly
			(pts
				(xy -0.3048 -0.1016) (xy -0.3048 0.9906) (xy 0.3048 0.9906) (xy 0.3048 -0.1016)
			)
			(stroke
				(width 0)
				(type default)
			)
			(fill no)
			(layer "B.CrtYd")
		)
		(fp_line
			(start -0.3048 -0.1016)
			(end 0.3048 -0.1016)
			(stroke
				(width 0.1)
				(type default)
			)
			(layer "B.Fab")
		)
		(fp_line
			(start -0.3048 0.9906)
			(end -0.3048 -0.1016)
			(stroke
				(width 0.1)
				(type default)
			)
			(layer "B.Fab")
		)
		(fp_line
			(start 0.3048 -0.1016)
			(end 0.3048 0.9906)
			(stroke
				(width 0.1)
				(type default)
			)
			(layer "B.Fab")
		)
		(fp_line
			(start 0.3048 0.9906)
			(end -0.3048 0.9906)
			(stroke
				(width 0.1)
				(type default)
			)
			(layer "B.Fab")
		)
		(pad "1" smd rect
			(at 0 0 180)
			(size 0.508 0.508)
			(layers "B.Cu" "B.Mask" "B.Paste")
			(net "VR_PVCCIO_CPU0_VD12")
		)
		(pad "2" smd rect
			(at 0 0.889 180)
			(size 0.508 0.508)
			(layers "B.Cu" "B.Mask" "B.Paste")
			(net "GND")
		)
		(zone
			(layer "B.Cu")
			(hatch none 0.5)
			(connect_pads
				(clearance 0)
			)
			(min_thickness 0.25)
			(keepout
				(tracks allowed)
				(vias not_allowed)
				(pads allowed)
				(copperpour not_allowed)
				(footprints allowed)
			)
			(placement
				(enabled no)
				(sheetname "")
			)
			(fill
				(thermal_gap 0.5)
				(thermal_bridge_width 0.5)
				(island_removal_mode 0)
			)
			(polygon
				(pts
					(xy 348.488 -83.2866) (xy 347.98 -83.2866) (xy 347.98 -82.9056) (xy 348.488 -82.9056)
				)
			)
		)
		(zone
			(layer "B.Cu")
			(hatch none 0.5)
			(connect_pads
				(clearance 0)
			)
			(min_thickness 0.25)
			(keepout
				(tracks not_allowed)
				(vias allowed)
				(pads allowed)
				(copperpour not_allowed)
				(footprints allowed)
			)
			(placement
				(enabled no)
				(sheetname "")
			)
			(fill
				(thermal_gap 0.5)
				(thermal_bridge_width 0.5)
				(island_removal_mode 0)
			)
			(polygon
				(pts
					(xy 348.488 -82.9056) (xy 347.98 -82.9056) (xy 347.98 -83.2866) (xy 348.488 -83.2866)
				)
			)
		)
	)
)
